FILE_TYPE=LIBRARY_PARTS;
primitive 'ADM1085','ADM1085_SMT';
  pin
    'CEXT':
      PIN_NUMBER='(5)';
      PIN_TYPE='ANALOG';
      NO_LOAD_CHECK='Both';
      NO_IO_CHECK='Both';
      NO_ASSERT_CHECK='TRUE';
      NO_DIR_CHECK='TRUE';
      ALLOW_CONNECT='TRUE';
    'ENIN':
      PIN_NUMBER='(1)';
      INPUT_LOAD='(-0.01,0.01)';
    'ENOUT':
      PIN_NUMBER='(4)';
      OUTPUT_LOAD='(1.0,-1.0)';
    'GND':
      PIN_NUMBER='(2)';
      PINUSE='GROUND';
      NO_LOAD_CHECK='Both';
      NO_IO_CHECK='Both';
      NO_ASSERT_CHECK='TRUE';
      NO_DIR_CHECK='TRUE';
      ALLOW_CONNECT='TRUE';
    'VCC':
      PIN_NUMBER='(6)';
      PINUSE='POWER';
      NO_LOAD_CHECK='Both';
      NO_IO_CHECK='Both';
      NO_ASSERT_CHECK='TRUE';
      NO_DIR_CHECK='TRUE';
      ALLOW_CONNECT='TRUE';
    'VIN':
      PIN_NUMBER='(3)';
      INPUT_LOAD='(-0.01,0.01)';
  end_pin;
  body
    PART_NAME='ADM1085';
    PHYS_DES_PREFIX='U';
  end_body;
end_primitive;

END.
